INTEGER-PLACES         2
DECIMAL-PLACES         5
X-OFFSET               0.000000
Y-OFFSET               0.000000
FEEDRATE               1
COORDINATES            ABSOLUTE
OUTPUT-UNITS           ENGLISH
TOOL-ORDER             INCREASING
REPEAT-CODES           NO
SUPPRESS-LEAD-ZEROES   NO
SUPPRESS-TRAIL-ZEROES  NO
SUPPRESS-EQUAL         NO
TOOL-SELECT            NO
OPTIMIZE_DRILLING      NO
ENHANCED_EXCELLON      NO
HEADER                 none
LEADER                 12
CODE                   ASCII
SEPARATE               NO
SEPARATE-ROUTING       NO
DRILLING               LAYER-PAIR
BACKDRILL              YES
CAVITY                 NO
COUNTER                NO
TOLERANCE_DRILL        NO
TOLERANCE_TRAVEL       NO
TOOL_SIZE              NO
ROTATION               NO
NON_STANDARD           NO
TOTAL_DRILL            NO
SEPARATE_SLOT          NO
SUPPRESS_TOLERANCE     NO
SUPPRESS_TOOLSIZE      NO
SUPPRESS_ROTATION      NO
